# T6G (Grand Teton) — schematic parts with pin connectivity, parts 1–169 of 8303; source: Cadence DE-HDL packaged netlist (pstxprt.dat, pstxnet.dat, pstchip.dat)

BT2  CONN2_AAABAT029Y19  CONN2_AAA-BAT-029-Y19 IO  pkg BATTERY_AAA-BAT-029-Y19  page 187 : 1 = P3V_BAT ; 2 = GND
C1  Q_CAP  0.1UF 25V 10% X7R  pkg 0402  page 238 : 1 = P3V3_AUX ; 2 = GND
C2  Q_CAP  0.1UF 25V 10% X7R  pkg 0402  page 160 : 1 = P3V3_AUX ; 2 = GND
C3  Q_CAP  0.1UF 25V 10% X7R  pkg 0402  page 160 : 1 = PVDD11_S3_P0 ; 2 = GND
C4  Q_CAP  0.1UF 25V 10% X7R  pkg 0402  page 124 : 1 = GPU_3V3IO_RSVD1_ISO ; 2 = GND
C5  Q_CAP  0.1UF 25V 10% X7R  pkg 0402  page 124 : 1 = GPU_3V3IO_RSVD4_ISO ; 2 = GND
C6  Q_CAP  0.1UF 25V 10% EMPTY  pkg 0402  page 124 : 1 = HGX_DETECT_N_ISO ; 2 = GND
C7  Q_CAP  0.1UF 25V 10% X7R  pkg 0402  page 124 : 1 = GPU_3V3IO_RSVD3_ISO ; 2 = GND
C8  Q_CAP  0.1UF 25V 10% X7R  pkg 0402  page 124 : 1 = P3V3_AUX ; 2 = GND
C9  Q_CAP  1UF 25V 10% EMPTY  pkg C0402  page 161 : 1 = I3C_MUX_CPU0_VIO ; 2 = GND
C10  Q_CAP  0.1UF 25V 10% X7R  pkg 0402  page 133 : 1 = P3V3_AUX ; 2 = GND
C11  Q_CAP  0.1UF 25V 10% X7R  pkg 0402  page 161 : 1 = P3V3_AUX ; 2 = GND
C12  Q_CAP  0.1UF 25V 10% X7R  pkg 0402  page 125 : 1 = GPU_3V3IO_RSVD0_FFU_ISO ; 2 = GND
C13  Q_CAP  0.1UF 25V 10% X7R  pkg 0402  page 125 : 1 = PRSNT_CABLE_GPU_B3_ISO_N ; 2 = GND
C14  Q_CAP  0.1UF 25V 10% X7R  pkg 0402  page 125 : 1 = GPU_3V3IO_RSVD1_FFU_ISO ; 2 = GND
C15  Q_CAP  0.1UF 25V 10% X7R  pkg 0402  page 125 : 1 = PRSNT_CABLE_GPU_A1_ISO_N ; 2 = GND
C16  Q_CAP  0.1UF 25V 10% X7R  pkg 0402  page 125 : 1 = GPU_3V3IO_RSVD3_FFU_ISO ; 2 = GND
C17  Q_CAP  0.1UF 25V 10% X7R  pkg 0402  page 125 : 1 = GPU_3V3IO_RSVD5_FFU_ISO ; 2 = GND
C18  Q_CAP  0.1UF 25V 10% X7R  pkg 0402  page 125 : 1 = SWB_HSC_PWRGD_ISO ; 2 = GND
C19  Q_CAP  0.1UF 25V 10% X7R  pkg 0402  page 125 : 1 = PRSNT_CABLE_GPU_A2_ISO_N ; 2 = GND
C20  Q_CAP  0.1UF 16V 10% X7R  pkg C0402  page 85 : 1 = P3V3_AUX ; 2 = GND
C21  Q_CAP  0.1UF 25V 10% X7R  pkg 0402  page 131 : 1 = P12V_OCP_SFF_R ; 2 = GND
C22  Q_CAP  0.01UF 50V 10% EMPTY  pkg C0402  page 187 : 1 = U9_NR ; 2 = GND
C23  Q_CAP  0.1UF 25V 10% X7R  pkg 0402  page 160 : 1 = P3V3_AUX ; 2 = GND
C24  Q_CAP  10UF 6.3V 20% EMPTY  pkg C0402  page 161 : 1 = PVDD18_S5_P0 ; 2 = GND
C25  Q_CAP  0.1UF 25V 10% X7R  pkg 0402  page 161 : 1 = P3V3_AUX ; 2 = GND
C26  Q_CAP  0.1UF 25V 10% X7R  pkg 0402  page 160 : 1 = P3V3 ; 2 = GND
C27  Q_CAP  0.1UF 25V 10% X7R  pkg 0402  page 131 : 1 = P12V_OCP_SFF_R ; 2 = GND
C28  Q_CAP  10UF 6.3V 20% X6S  pkg C0402  page 183 : 1 = P3V3_9ZXL045_P1_VDD ; 2 = GND
C29  Q_CAP  0.22UF 25V 10% X7R  pkg C0402  page 188 : 1 = SW_P3V3_EN_ISO_R ; 2 = GND
C30  Q_CAP  0.1UF 25V 10% X7R  pkg 0402  page 29 : 1 = P1V8_AUX ; 2 = GND
C31  Q_CAP  0.1UF 25V 10% X7R  pkg 0402  page 235 : 1 = P3V3_AUX ; 2 = GND
C32  Q_CAP  0.1UF 25V 10% X7R  pkg 0402  page 235 : 1 = P3V3_AUX ; 2 = GND
C33  Q_CAP  0.1UF 25V 10% X7R  pkg 0402  page 257 : 1 = P12V_OCP_V3_2_ISENSE_TIC ; 2 = GND
C34  Q_CAP  22UF 16V 20% X6S  pkg C0805  page 131 : 1 = P12V_OCP_SFF_R ; 2 = GND
C35  Q_CAP  100PF 50V 5% EMPTY  pkg 0402  page 257 : 1 = P12V_E1S_0_ISENSE_MAM ; 2 = GND
C36  Q_CAP  0.1UF 25V 10% X7R  pkg 0402  page 133 : 1 = P3V3_AUX ; 2 = GND
C37  Q_CAP  0.1UF 25V 10% X7R  pkg 0402  page 257 : 1 = P12V_OCP_SFF_ISENSE_TIC ; 2 = GND
C38  Q_CAP  0.1UF 25V 10% X7R  pkg 0402  page 139 : 1 = P3V3_AUX ; 2 = GND
C39  Q_CAP  1UF 25V 10% X6S  pkg C0402  page 140 : 1 = P3V3_OCP_VCC_2 ; 2 = GND
C40  Q_CAP  0.01UF 50V 10% EMPTY  pkg C0402  page 140 : 1 = P12V_OCP_V3_2 ; 2 = P12V_OCP_GATE_2
C41  Q_CAP_DIFFBUS  DIFF BUS_0.22UF 6.3V 20% X6S  pkg C0201  page 65 : 1 = P5E_CPU0_G3_TX_C_DN<12> ; 2 = P5E_CPU0_G3_TX_DN<12>
C42  Q_CAP  0.1UF 25V 10% X7R  pkg 0402  page 34 : 1 = PVDD18_S5_P0 ; 2 = GND
C43  Q_CAP  0.1UF 25V 10% X7R  pkg 0402  page 34 : 1 = P3V3_AUX ; 2 = GND
C44  Q_CAP_DIFFBUS  DIFF BUS_0.22UF 6.3V 20% X6S  pkg C0201  page 65 : 1 = P5E_CPU0_G3_TX_C_DP<8> ; 2 = P5E_CPU0_G3_TX_DP<8>
C45  Q_CAP  1UF 25V 10% X6S  pkg C0402  page 187 : 1 = P1V5_BAT_IN ; 2 = GND
C46  Q_CAP_DIFFBUS  DIFF BUS_0.22UF 6.3V 20% X6S  pkg C0201  page 65 : 1 = P5E_CPU0_G3_TX_C_DN<7> ; 2 = P5E_CPU0_G3_TX_DN<7>
C47  Q_CAP_DIFFBUS  DIFF BUS_0.22UF 6.3V 20% X6S  pkg C0201  page 65 : 1 = P5E_CPU0_G3_TX_C_DP<6> ; 2 = P5E_CPU0_G3_TX_DP<6>
C48  Q_CAP_DIFFBUS  DIFF BUS_0.22UF 6.3V 20% X6S  pkg C0201  page 67 : 1 = P5E_CPU1_P3_TX_C_DN<15> ; 2 = P5E_CPU1_P3_TX_DN<15>
C49  Q_CAP_DIFFBUS  DIFF BUS_0.22UF 6.3V 20% X6S  pkg C0201  page 67 : 1 = P5E_CPU1_P3_TX_C_DP<15> ; 2 = P5E_CPU1_P3_TX_DP<15>
C50  Q_CAP_DIFFBUS  DIFF BUS_0.22UF 6.3V 20% X6S  pkg C0201  page 67 : 1 = P5E_CPU1_P3_TX_C_DN<14> ; 2 = P5E_CPU1_P3_TX_DN<14>
C51  Q_CAP_DIFFBUS  DIFF BUS_0.22UF 6.3V 20% X6S  pkg C0201  page 67 : 1 = P5E_CPU1_P3_TX_C_DP<14> ; 2 = P5E_CPU1_P3_TX_DP<14>
C52  Q_CAP_DIFFBUS  DIFF BUS_0.22UF 6.3V 20% X6S  pkg C0201  page 67 : 1 = P5E_CPU1_P3_TX_C_DN<13> ; 2 = P5E_CPU1_P3_TX_DN<13>
C53  Q_CAP_DIFFBUS  DIFF BUS_0.22UF 6.3V 20% X6S  pkg C0201  page 67 : 1 = P5E_CPU1_P3_TX_C_DP<13> ; 2 = P5E_CPU1_P3_TX_DP<13>
C54  Q_CAP_DIFFBUS  DIFF BUS_0.22UF 6.3V 20% X6S  pkg C0201  page 67 : 1 = P5E_CPU1_P3_TX_C_DN<12> ; 2 = P5E_CPU1_P3_TX_DN<12>
C55  Q_CAP_DIFFBUS  DIFF BUS_0.22UF 6.3V 20% X6S  pkg C0201  page 67 : 1 = P5E_CPU1_P3_TX_C_DP<12> ; 2 = P5E_CPU1_P3_TX_DP<12>
C56  Q_CAP_DIFFBUS  DIFF BUS_0.22UF 6.3V 20% X6S  pkg C0201  page 67 : 1 = P5E_CPU1_G1_TX_C_DP<8> ; 2 = P5E_CPU1_G1_TX_DP<8>
C57  Q_CAP  10UF 16V 10% EMPTY  pkg C0805  page 188 : 1 = P5V_AUX ; 2 = GND
C58  Q_CAP  0.1UF 25V 10% X7R  pkg 0402  page 183 : 1 = P3V3_9ZXL045_P1_VDD ; 2 = GND
C59  Q_CAP  100PF 50V 5% EMPTY  pkg 0402  page 257 : 1 = P12V_OCP_V3_2_ISENSE_MAM ; 2 = GND
C60  Q_CAP  10UF 16V 10% EMPTY  pkg C0805  page 188 : 1 = P3V3_AUX ; 2 = GND
C61  Q_CAP  100NF 50V 10% X7R  pkg C0402  page 188 : 1 = P3V3 ; 2 = GND
C62  Q_CAP  220PF 50V 5% C0G  pkg C0402  page 151 : 1 = UART_CPU0_SCM_LVC3_UART1_TX ; 2 = GND
C63  Q_CAP  220PF 50V 5% C0G  pkg C0402  page 151 : 1 = UART_CPU0_SCM_LVC3_UART1_R_RX ; 2 = GND
C64  Q_CAP  0.1UF 25V 10% EMPTY  pkg 0402  page 240 : 1 = PDB_PRSNT_N ; 2 = GND
C65  Q_CAP  0.1UF 25V 10% EMPTY  pkg 0402  page 240 : 1 = HPDB_HSC_PWRGD_R ; 2 = GND
C66  Q_CAP  0.1UF 25V 10% EMPTY  pkg 0402  page 240 : 1 = FM_FAN_PWR_EN_R ; 2 = GND
C67  Q_CAP  0.1UF 25V 10% EMPTY  pkg 0402  page 240 : 1 = FM_GPU_HSC_EN_BUF_R1 ; 2 = GND
C68  Q_CAP  0.1UF 25V 10% X7R  pkg 0402  page 183 : 1 = P3V3_9ZXL045_P1_VDDA ; 2 = GND
C69  Q_CAP  0.1UF 25V 10% X7R  pkg 0402  page 241 : 1 = P3V3_AUX ; 2 = GND
C70  Q_CAP  0.1UF 25V 10% X7R  pkg 0402  page 241 : 1 = HPDB_HSC_PWRGD_ISO ; 2 = GND
C71  Q_CAP  4.7PF 50V 0.1P NPO  pkg C0402  page 233 : 1 = CLK_GEN2_XTAL_IN_R ; 2 = GND
C72  Q_CAP  0.1UF 25V 10% X7R  pkg 0402  page 133 : 1 = P3V3_AUX ; 2 = GND
C73  Q_CAP  0.1UF 25V 10% X7R  pkg 0402  page 235 : 1 = P3V3_AUX ; 2 = GND
C74  Q_CAP  0.1UF 25V 10% EMPTY  pkg 0402  page 240 : 1 = RST_SMB_SWITCH_R_N ; 2 = GND
C75  Q_CAP  0.1UF 25V 10% X7R  pkg 0402  page 183 : 1 = P3V3_9ZXL045_P1_VDD ; 2 = GND
C76  Q_CAP  10UF 6.3V 20% X6S  pkg C0402  page 182 : 1 = P3V3_9ZXL045_P0_VDDA ; 2 = GND
C77  Q_CAP  10UF 6.3V 20% X6S  pkg C0402  page 182 : 1 = P3V3_9ZXL045_P0_VDDR ; 2 = GND
C78  Q_CAP  0.1UF 25V 10% X7R  pkg 0402  page 182 : 1 = P3V3_9ZXL045_P0_VDDR ; 2 = GND
C79  Q_CAP  0.1UF 25V 10% X7R  pkg 0402  page 182 : 1 = P3V3_9ZXL045_P0_VDD ; 2 = GND
C80  Q_CAP  0.1UF 25V 10% X7R  pkg 0402  page 182 : 1 = P3V3_9ZXL045_P0_VDD ; 2 = GND
C81  Q_CAP  0.1UF 25V 10% X7R  pkg 0402  page 182 : 1 = P3V3_9ZXL045_P0_VDD ; 2 = GND
C82  Q_CAP  10UF 6.3V 20% X6S  pkg C0402  page 183 : 1 = P3V3_9ZXL045_P1_VDDA ; 2 = GND
C83  Q_CAP  10UF 6.3V 20% X6S  pkg C0402  page 183 : 1 = P3V3_9ZXL045_P1_VDDR ; 2 = GND
C84  Q_CAP  0.1UF 25V 10% X7R  pkg 0402  page 183 : 1 = P3V3_9ZXL045_P1_VDDR ; 2 = GND
C85  Q_CAP  0.001UF 50V 10% X7R  pkg C0402  page 172 : 1 = HDT_HDR_TRST_N ; 2 = GND
C86  Q_CAP  0.01UF 50V 10% EMPTY  pkg C0402  page 172 : 1 = JTAG_TDI ; 2 = GND
C87  Q_CAP  0.001UF 50V 10% X7R  pkg C0402  page 172 : 1 = HDT_HDR_DBREQ_N ; 2 = GND
C88  Q_CAP  0.1UF 25V 10% X7R  pkg 0402  page 86 : 1 = P3V3_AUX ; 2 = GND
C89  Q_CAP  10UF 25V 10% X6S  pkg C0805  page 86 : 1 = P12V_MEM_CPU0 ; 2 = GND
C90  Q_CAP  0.1UF 25V 10% X7R  pkg 0402  page 183 : 1 = P3V3_9ZXL045_P1_VDD ; 2 = GND
C91  Q_CAP  12PF 50V 5% C0G  pkg C0402  page 176 : 1 = XTAL_USB_CPU0_HUB1_XIN ; 2 = GND
C92  Q_CAP  0.1UF 25V 10% X7R  pkg 0402  page 87 : 1 = P3V3_AUX ; 2 = GND
C93  Q_CAP  15PF 50V 5% C0G  pkg 0402  page 176 : 1 = XTAL_USB_CPU0_HUB1_XOUT ; 2 = GND
C94  Q_CAP  4.7PF 50V 0.1P NPO  pkg C0402  page 233 : 1 = CLK_GEN2_XTAL_OUT ; 2 = GND
C95  Q_CAP  0.1UF 25V 10% X7R  pkg 0402  page 233 : 1 = VFG3P3_CLK_GEN ; 2 = GND
C96  Q_CAP  0.1UF 25V 10% X7R  pkg 0402  page 88 : 1 = P3V3_AUX ; 2 = GND
C97  Q_CAP  0.1UF 25V 10% X7R  pkg 0402  page 233 : 1 = VFG_3P3A_CLK_GEN ; 2 = GND
C98  Q_CAP  0.1UF 25V 10% X7R  pkg 0402  page 183 : 1 = P3V3_9ZXL045_P1_VDD ; 2 = GND
C99  Q_CAP  0.1UF 25V 10% X7R  pkg 0402  page 183 : 1 = P3V3_9ZXL045_P1_VDD ; 2 = GND
C100  Q_CAP  0.1UF 25V 10% X7R  pkg 0402  page 89 : 1 = P3V3_AUX ; 2 = GND
C101  Q_CAP  1000PF 50V 5% EMPTY  pkg 0402  page 362 : 1 = PWRGD_P0V9_RETIMER_CPU0_R ; 2 = GND
C102  Q_CAP  100UF 4V 20% X6S  pkg C0805  page 334 : 1 = P1V8_CPU1_RT_1D ; 2 = GND
C103  Q_CAP  100UF 4V 20% X6S  pkg C0805  page 334 : 1 = P1V8_CPU1_RT1_1A ; 2 = GND
C104  Q_CAP  0.1UF 25V 10% X7R  pkg 0402  page 90 : 1 = P3V3_AUX ; 2 = GND
C105  Q_CAP  0.1UF 25V 10% EMPTY  pkg 0402  page 361 : 1 = P1V8_RETIMER_CPU1_EN ; 2 = GND
C106  Q_CAP  0.1UF 25V 10% X7R  pkg 0402  page 250 : 1 = P3V3_AUX ; 2 = GND
C107  Q_CAP  1000PF 50V 5% EMPTY  pkg 0402  page 364 : 1 = PWRGD_P0V9_RETIMER_CPU1_R ; 2 = GND
C108  Q_CAP  0.1UF 25V 10% X7R  pkg 0402  page 91 : 1 = P3V3_AUX ; 2 = GND
C109  Q_CAP  1000PF 50V 5% X7R  pkg 0402  page 361 : 1 = FM_PWRGD_P1V8_RETIMER_CPU1 ; 2 = GND
C110  Q_CAP  22UF 4V 20% X6S  pkg C0402  page 334 : 1 = P1V8_CPU1_RT_1D ; 2 = GND
C111  Q_CAP  22UF 4V 20% X6S  pkg C0402  page 334 : 1 = P1V8_CPU1_RT1_1A ; 2 = GND
C112  Q_CAP  0.1UF 25V 10% X7R  pkg 0402  page 92 : 1 = P3V3_AUX ; 2 = GND
C113  Q_CAP  100UF 4V 20% X6S  pkg C0805  page 323 : 1 = P1V8_CPU1_RT_1D ; 2 = GND
C114  Q_CAP  100UF 4V 20% X6S  pkg C0805  page 323 : 1 = P1V8_CPU1_RT0_1A ; 2 = GND
C115  Q_CAP  22UF 4V 20% X6S  pkg C0402  page 323 : 1 = P1V8_CPU1_RT_1D ; 2 = GND
C116  Q_CAP  0.1UF 25V 10% X7R  pkg 0402  page 93 : 1 = P3V3_AUX ; 2 = GND
C117  Q_CAP  22UF 4V 20% X6S  pkg C0402  page 323 : 1 = P1V8_CPU1_RT0_1A ; 2 = GND
C118  Q_CAP  10UF 6.3V 20% X6S  pkg C0402  page 323 : 1 = P1V8_CPU1_RT_1D ; 2 = GND
C119  Q_CAP  10UF 6.3V 20% X6S  pkg C0402  page 323 : 1 = P1V8_CPU1_RT0_1A ; 2 = GND
C120  Q_CAP  0.1UF 25V 10% X7R  pkg 0402  page 94 : 1 = P3V3_AUX ; 2 = GND
C121  Q_CAP  4.7UF 6.3V 20% X6S  pkg 0402  page 323 : 1 = P1V8_CPU1_RT0_1A ; 2 = GND
C122  Q_CAP  4.7UF 6.3V 20% X6S  pkg 0402  page 323 : 1 = P1V8_CPU1_RT_1D ; 2 = GND
C123  Q_CAP  1UF 4V 20% X6S  pkg 0201  page 323 : 1 = P1V8_CPU1_RT0_1A ; 2 = GND
C124  Q_CAP  0.1UF 25V 10% X7R  pkg 0402  page 95 : 1 = P3V3_AUX ; 2 = GND
C125  Q_CAP  1UF 4V 20% X6S  pkg 0201  page 323 : 1 = P1V8_CPU1_RT0_1A_1D ; 2 = GND
C126  Q_CAP  1UF 4V 20% X6S  pkg 0201  page 323 : 1 = P1V8_CPU1_RT0_1A ; 2 = GND
C127  Q_CAP  10UF 6.3V 20% X6S  pkg C0402  page 334 : 1 = P1V8_CPU1_RT_1D ; 2 = GND
C128  Q_CAP  0.1UF 25V 10% X7R  pkg 0402  page 96 : 1 = P3V3_AUX ; 2 = GND
C129  Q_CAP  0.1UF 10V 10% X7S  pkg C0201  page 323 : 1 = P1V8_CPU1_RT0_1A ; 2 = GND
C130  Q_CAP  0.1UF 10V 10% X7S  pkg C0201  page 323 : 1 = P1V8_CPU1_RT0_1A_1D ; 2 = GND
C131  Q_CAP  0.1UF 10V 10% X7S  pkg C0201  page 323 : 1 = P1V8_CPU1_RT0_1A ; 2 = GND
C132  Q_CAP  0.1UF 25V 10% X7R  pkg 0402  page 97 : 1 = P3V3_AUX ; 2 = GND
C133  Q_CAP  0.1UF 10V 10% X7S  pkg C0201  page 323 : 1 = P1V8_CPU1_RT0_1A ; 2 = GND
C134  Q_CAP  0.1UF 10V 10% X7S  pkg C0201  page 323 : 1 = P1V8_CPU1_RT0_1A ; 2 = GND
C135  Q_CAP  1UF 4V 20% X6S  pkg 0201  page 323 : 1 = P0V9_CPU1_RT0_2A ; 2 = GND
C136  Q_CAP  0.1UF 25V 10% X7R  pkg 0402  page 98 : 1 = P3V3_AUX ; 2 = GND
C137  Q_CAP  0.1UF 10V 10% X7S  pkg C0201  page 323 : 1 = P0V9_CPU1_RT_2D ; 2 = GND
C138  Q_CAP  1UF 4V 20% X6S  pkg 0201  page 323 : 1 = P0V9_CPU1_RT0_2A ; 2 = GND
C139  Q_CAP  0.1UF 10V 10% X7S  pkg C0201  page 323 : 1 = P0V9_CPU1_RT_2D ; 2 = GND
C140  Q_CAP  0.1UF 25V 10% X7R  pkg 0402  page 99 : 1 = P3V3_AUX ; 2 = GND
C141  Q_CAP  0.1UF 10V 10% X7S  pkg C0201  page 323 : 1 = P0V9_CPU1_RT0_2A ; 2 = GND
C142  Q_CAP  10UF 25V 10% X6S  pkg C0805  page 86 : 1 = P12V_MEM_CPU0 ; 2 = GND
C143  Q_CAP  10UF 25V 10% X6S  pkg C0805  page 87 : 1 = P12V_MEM_CPU0 ; 2 = GND
C144  Q_CAP  0.1UF 25V 10% X7R  pkg 0402  page 100 : 1 = P3V3_AUX ; 2 = GND
C145  Q_CAP  10UF 25V 10% X6S  pkg C0805  page 87 : 1 = P12V_MEM_CPU0 ; 2 = GND
C146  Q_CAP  10UF 25V 10% X6S  pkg C0805  page 88 : 1 = P12V_MEM_CPU0 ; 2 = GND
C147  Q_CAP  10UF 25V 10% X6S  pkg C0805  page 88 : 1 = P12V_MEM_CPU0 ; 2 = GND
C148  Q_CAP  0.1UF 25V 10% X7R  pkg 0402  page 101 : 1 = P3V3_AUX ; 2 = GND
C149  Q_CAP  10UF 25V 10% X6S  pkg C0805  page 89 : 1 = P12V_MEM_CPU0 ; 2 = GND
C150  Q_CAP  10UF 25V 10% X6S  pkg C0805  page 89 : 1 = P12V_MEM_CPU0 ; 2 = GND
C151  Q_CAP  10UF 25V 10% X6S  pkg C0805  page 90 : 1 = P12V_MEM_CPU0 ; 2 = GND
C152  Q_CAP  0.1UF 25V 10% X7R  pkg 0402  page 102 : 1 = P3V3_AUX ; 2 = GND
C153  Q_CAP  10UF 25V 10% X6S  pkg C0805  page 90 : 1 = P12V_MEM_CPU0 ; 2 = GND
C154  Q_CAP  10UF 25V 10% X6S  pkg C0805  page 91 : 1 = P12V_MEM_CPU0 ; 2 = GND
C155  Q_CAP  10UF 25V 10% X6S  pkg C0805  page 91 : 1 = P12V_MEM_CPU0 ; 2 = GND
C156  Q_CAP  0.1UF 25V 10% X7R  pkg 0402  page 103 : 1 = P3V3_AUX ; 2 = GND
C157  Q_CAP  10UF 25V 10% X6S  pkg C0805  page 92 : 1 = P12V_MEM_CPU0 ; 2 = GND
C158  Q_CAP  10UF 25V 10% X6S  pkg C0805  page 92 : 1 = P12V_MEM_CPU0 ; 2 = GND
C159  Q_CAP  10UF 25V 10% X6S  pkg C0805  page 93 : 1 = P12V_MEM_CPU0 ; 2 = GND
C160  Q_CAP  0.1UF 25V 10% X7R  pkg 0402  page 104 : 1 = P3V3_AUX ; 2 = GND
C161  Q_CAP  10UF 25V 10% X6S  pkg C0805  page 93 : 1 = P12V_MEM_CPU0 ; 2 = GND
C162  Q_CAP  10UF 25V 10% X6S  pkg C0805  page 94 : 1 = P12V_MEM_CPU0 ; 2 = GND
C163  Q_CAP  10UF 25V 10% X6S  pkg C0805  page 94 : 1 = P12V_MEM_CPU0 ; 2 = GND
C164  Q_CAP  0.1UF 25V 10% X7R  pkg 0402  page 105 : 1 = P3V3_AUX ; 2 = GND
C165  Q_CAP  10UF 25V 10% X6S  pkg C0805  page 95 : 1 = P12V_MEM_CPU0 ; 2 = GND
C166  Q_CAP  10UF 25V 10% X6S  pkg C0805  page 95 : 1 = P12V_MEM_CPU0 ; 2 = GND
C167  Q_CAP  10UF 25V 10% X6S  pkg C0805  page 96 : 1 = P12V_MEM_CPU0 ; 2 = GND
C168  Q_CAP  0.1UF 25V 10% X7R  pkg 0402  page 106 : 1 = P3V3_AUX ; 2 = GND
